FILE_TYPE = CONNECTIVITY;
{Allegro Design Entry HDL 16.6-p007 (v16-6-112F) 10/10/2012}
"PAGE_NUMBER" = 65;
0"NC";
1"TP_P3E_CPU1_PE2_RSR_TXN<15:0>";
2"TP_P3E_CPU1_PE2_RSR_TXP<15:0>";
3"TP_P3E_CPU1_PE2_RSR_RXN<15:0>";
4"TP_P3E_CPU1_PE2_RSR_RXP<15:0>";
5"TP_P3E_CPU1_PE2_RSR_TXN<14>";
6"TP_P3E_CPU1_PE2_RSR_RXP<9>";
7"TP_P3E_CPU1_PE2_RSR_RXP<11>";
8"TP_P3E_CPU1_PE2_RSR_RXN<14>";
9"TP_P3E_CPU1_PE2_RSR_RXP<10>";
10"TP_P3E_CPU1_PE2_RSR_RXP<0>";
11"TP_P3E_CPU1_PE2_RSR_RXP<1>";
12"TP_P3E_CPU1_PE2_RSR_RXP<2>";
13"TP_P3E_CPU1_PE2_RSR_RXP<3>";
14"TP_P3E_CPU1_PE2_RSR_RXN<0>";
15"TP_P3E_CPU1_PE2_RSR_RXN<1>";
16"TP_P3E_CPU1_PE2_RSR_RXN<2>";
17"TP_P3E_CPU1_PE2_RSR_RXN<3>";
18"TP_P3E_CPU1_PE2_RSR_RXP<4>";
19"TP_P3E_CPU1_PE2_RSR_RXP<5>";
20"TP_P3E_CPU1_PE2_RSR_RXP<6>";
21"TP_P3E_CPU1_PE2_RSR_RXP<7>";
22"TP_P3E_CPU1_PE2_RSR_RXP<8>";
23"TP_P3E_CPU1_PE2_RSR_RXP<12>";
24"TP_P3E_CPU1_PE2_RSR_RXP<13>";
25"TP_P3E_CPU1_PE2_RSR_RXP<14>";
26"TP_P3E_CPU1_PE2_RSR_RXP<15>";
27"TP_P3E_CPU1_PE2_RSR_RXN<4>";
28"TP_P3E_CPU1_PE2_RSR_RXN<5>";
29"TP_P3E_CPU1_PE2_RSR_RXN<6>";
30"TP_P3E_CPU1_PE2_RSR_RXN<7>";
31"TP_P3E_CPU1_PE2_RSR_RXN<8>";
32"TP_P3E_CPU1_PE2_RSR_RXN<9>";
33"TP_P3E_CPU1_PE2_RSR_RXN<10>";
34"TP_P3E_CPU1_PE2_RSR_RXN<11>";
35"TP_P3E_CPU1_PE2_RSR_RXN<12>";
36"TP_P3E_CPU1_PE2_RSR_RXN<13>";
37"TP_P3E_CPU1_PE2_RSR_RXN<15>";
38"TP_P3E_CPU1_PE2_RSR_TXP<0>";
39"TP_P3E_CPU1_PE2_RSR_TXP<1>";
40"TP_P3E_CPU1_PE2_RSR_TXP<2>";
41"TP_P3E_CPU1_PE2_RSR_TXP<3>";
42"TP_P3E_CPU1_PE2_RSR_TXN<0>";
43"TP_P3E_CPU1_PE2_RSR_TXN<1>";
44"TP_P3E_CPU1_PE2_RSR_TXN<2>";
45"TP_P3E_CPU1_PE2_RSR_TXN<3>";
46"TP_P3E_CPU1_PE2_RSR_TXP<4>";
47"TP_P3E_CPU1_PE2_RSR_TXP<5>";
48"TP_P3E_CPU1_PE2_RSR_TXP<6>";
49"TP_P3E_CPU1_PE2_RSR_TXP<7>";
50"TP_P3E_CPU1_PE2_RSR_TXP<8>";
51"TP_P3E_CPU1_PE2_RSR_TXP<9>";
52"TP_P3E_CPU1_PE2_RSR_TXP<10>";
53"TP_P3E_CPU1_PE2_RSR_TXP<11>";
54"TP_P3E_CPU1_PE2_RSR_TXP<12>";
55"TP_P3E_CPU1_PE2_RSR_TXP<13>";
56"TP_P3E_CPU1_PE2_RSR_TXP<14>";
57"TP_P3E_CPU1_PE2_RSR_TXP<15>";
58"TP_P3E_CPU1_PE2_RSR_TXN<4>";
59"TP_P3E_CPU1_PE2_RSR_TXN<5>";
60"TP_P3E_CPU1_PE2_RSR_TXN<6>";
61"TP_P3E_CPU1_PE2_RSR_TXN<7>";
62"TP_P3E_CPU1_PE2_RSR_TXN<8>";
63"TP_P3E_CPU1_PE2_RSR_TXN<9>";
64"TP_P3E_CPU1_PE2_RSR_TXN<10>";
65"TP_P3E_CPU1_PE2_RSR_TXN<11>";
66"TP_P3E_CPU1_PE2_RSR_TXN<12>";
67"TP_P3E_CPU1_PE2_RSR_TXN<13>";
68"TP_P3E_CPU1_PE2_RSR_TXN<15>";
%"TAP"
"1","(-5575,2125)","2","mstr_standard","I11";
;
CDS_LIB"mstr_standard"
BODY_TYPE"PLUMBING"
HDL_TAP"TRUE";
"B \NAC \NWC"3;
"S \NAC"
BN"4"27;
%"TAP"
"1","(-5575,2225)","2","mstr_standard","I12";
;
CDS_LIB"mstr_standard"
BODY_TYPE"PLUMBING"
HDL_TAP"TRUE";
"B \NAC \NWC"3;
"S \NAC"
BN"6"29;
%"TAP"
"1","(-5575,2175)","2","mstr_standard","I13";
;
CDS_LIB"mstr_standard"
BODY_TYPE"PLUMBING"
HDL_TAP"TRUE";
"B \NAC \NWC"3;
"S \NAC"
BN"5"28;
%"TAP"
"1","(-5575,2275)","2","mstr_standard","I14";
;
CDS_LIB"mstr_standard"
BODY_TYPE"PLUMBING"
HDL_TAP"TRUE";
"B \NAC \NWC"3;
"S \NAC"
BN"7"30;
%"TAP"
"1","(-5425,2025)","2","mstr_standard","I15";
;
CDS_LIB"mstr_standard"
BODY_TYPE"PLUMBING"
HDL_TAP"TRUE";
"B \NAC \NWC"4;
"S \NAC"
BN"3"13;
%"TAP"
"1","(-5425,2375)","2","mstr_standard","I16";
;
CDS_LIB"mstr_standard"
BODY_TYPE"PLUMBING"
HDL_TAP"TRUE";
"B \NAC \NWC"4;
"S \NAC"
BN"4"18;
%"TAP"
"1","(-5425,2425)","2","mstr_standard","I17";
;
CDS_LIB"mstr_standard"
BODY_TYPE"PLUMBING"
HDL_TAP"TRUE";
"B \NAC \NWC"4;
"S \NAC"
BN"5"19;
%"TAP"
"1","(-5425,2475)","2","mstr_standard","I18";
;
CDS_LIB"mstr_standard"
BODY_TYPE"PLUMBING"
HDL_TAP"TRUE";
"B \NAC \NWC"4;
"S \NAC"
BN"6"20;
%"TAP"
"1","(-5575,2625)","2","mstr_standard","I19";
;
CDS_LIB"mstr_standard"
BODY_TYPE"PLUMBING"
HDL_TAP"TRUE";
"B \NAC \NWC"3;
"S \NAC"
BN"8"31;
%"TAP"
"1","(-5575,2725)","2","mstr_standard","I20";
;
CDS_LIB"mstr_standard"
BODY_TYPE"PLUMBING"
HDL_TAP"TRUE";
"B \NAC \NWC"3;
"S \NAC"
BN"10"33;
%"TAP"
"1","(-5575,2675)","2","mstr_standard","I21";
;
CDS_LIB"mstr_standard"
BODY_TYPE"PLUMBING"
HDL_TAP"TRUE";
"B \NAC \NWC"3;
"S \NAC"
BN"9"32;
%"TAP"
"1","(-5575,2775)","2","mstr_standard","I22";
;
CDS_LIB"mstr_standard"
BODY_TYPE"PLUMBING"
HDL_TAP"TRUE";
"B \NAC \NWC"3;
"S \NAC"
BN"11"34;
%"TAP"
"1","(-5425,2525)","2","mstr_standard","I23";
;
CDS_LIB"mstr_standard"
BODY_TYPE"PLUMBING"
HDL_TAP"TRUE";
"B \NAC \NWC"4;
"S \NAC"
BN"7"21;
%"TAP"
"1","(-5425,2875)","2","mstr_standard","I24";
;
CDS_LIB"mstr_standard"
BODY_TYPE"PLUMBING"
HDL_TAP"TRUE";
"B \NAC \NWC"4;
"S \NAC"
BN"8"22;
%"TAP"
"1","(-5425,2925)","2","mstr_standard","I25";
;
CDS_LIB"mstr_standard"
BODY_TYPE"PLUMBING"
HDL_TAP"TRUE";
"B \NAC \NWC"4;
"S \NAC"
BN"9"6;
%"TAP"
"1","(-5425,2975)","2","mstr_standard","I26";
;
CDS_LIB"mstr_standard"
BODY_TYPE"PLUMBING"
HDL_TAP"TRUE";
"B \NAC \NWC"4;
"S \NAC"
BN"10"9;
%"TAP"
"1","(-5575,3125)","2","mstr_standard","I27";
;
CDS_LIB"mstr_standard"
BODY_TYPE"PLUMBING"
HDL_TAP"TRUE";
"B \NAC \NWC"3;
"S \NAC"
BN"12"35;
%"TAP"
"1","(-5575,3225)","2","mstr_standard","I28";
;
CDS_LIB"mstr_standard"
BODY_TYPE"PLUMBING"
HDL_TAP"TRUE";
"B \NAC \NWC"3;
"S \NAC"
BN"14"8;
%"TAP"
"1","(-5575,3175)","2","mstr_standard","I29";
;
CDS_LIB"mstr_standard"
BODY_TYPE"PLUMBING"
HDL_TAP"TRUE";
"B \NAC \NWC"3;
"S \NAC"
BN"13"36;
%"TAP"
"1","(-5575,1725)","2","mstr_standard","I3";
;
CDS_LIB"mstr_standard"
BODY_TYPE"PLUMBING"
HDL_TAP"TRUE";
"B \NAC \NWC"3;
"S \NAC"
BN"2"16;
%"TAP"
"1","(-5575,3275)","2","mstr_standard","I30";
;
CDS_LIB"mstr_standard"
BODY_TYPE"PLUMBING"
HDL_TAP"TRUE";
"B \NAC \NWC"3;
"S \NAC"
BN"15"37;
%"TAP"
"1","(-5425,3025)","2","mstr_standard","I31";
;
CDS_LIB"mstr_standard"
BODY_TYPE"PLUMBING"
HDL_TAP"TRUE";
"B \NAC \NWC"4;
"S \NAC"
BN"11"7;
%"TAP"
"1","(-5425,3375)","2","mstr_standard","I32";
;
CDS_LIB"mstr_standard"
BODY_TYPE"PLUMBING"
HDL_TAP"TRUE";
"B \NAC \NWC"4;
"S \NAC"
BN"12"23;
%"TAP"
"1","(-5425,3475)","2","mstr_standard","I33";
;
CDS_LIB"mstr_standard"
BODY_TYPE"PLUMBING"
HDL_TAP"TRUE";
"B \NAC \NWC"4;
"S \NAC"
BN"14"25;
%"TAP"
"1","(-5425,3425)","2","mstr_standard","I34";
;
CDS_LIB"mstr_standard"
BODY_TYPE"PLUMBING"
HDL_TAP"TRUE";
"B \NAC \NWC"4;
"S \NAC"
BN"13"24;
%"TAP"
"1","(-5425,3525)","2","mstr_standard","I35";
;
CDS_LIB"mstr_standard"
BODY_TYPE"PLUMBING"
HDL_TAP"TRUE";
"B \NAC \NWC"4;
"S \NAC"
BN"15"26;
%"TAP"
"1","(-2950,1975)","0","mstr_standard","I36";
;
CDS_LIB"mstr_standard"
BODY_TYPE"PLUMBING"
HDL_TAP"TRUE";
"B \NAC \NWC"2;
"S \NAC"
BN"2"40;
%"TAP"
"1","(-2950,1875)","0","mstr_standard","I37";
;
CDS_LIB"mstr_standard"
BODY_TYPE"PLUMBING"
HDL_TAP"TRUE";
"B \NAC \NWC"2;
"S \NAC"
BN"0"38;
%"TAP"
"1","(-2950,1925)","0","mstr_standard","I38";
;
CDS_LIB"mstr_standard"
BODY_TYPE"PLUMBING"
HDL_TAP"TRUE";
"B \NAC \NWC"2;
"S \NAC"
BN"1"39;
%"TAP"
"1","(-2800,1675)","0","mstr_standard","I39";
;
CDS_LIB"mstr_standard"
BODY_TYPE"PLUMBING"
HDL_TAP"TRUE";
"B \NAC \NWC"1;
"S \NAC"
BN"1"43;
%"TAP"
"1","(-5575,1675)","2","mstr_standard","I4";
;
CDS_LIB"mstr_standard"
BODY_TYPE"PLUMBING"
HDL_TAP"TRUE";
"B \NAC \NWC"3;
"S \NAC"
BN"1"15;
%"TAP"
"1","(-2800,1625)","0","mstr_standard","I40";
;
CDS_LIB"mstr_standard"
BODY_TYPE"PLUMBING"
HDL_TAP"TRUE";
"B \NAC \NWC"1;
"S \NAC"
BN"0"42;
%"TAP"
"1","(-2800,1725)","0","mstr_standard","I41";
;
CDS_LIB"mstr_standard"
BODY_TYPE"PLUMBING"
HDL_TAP"TRUE";
"B \NAC \NWC"1;
"S \NAC"
BN"2"44;
%"TAP"
"1","(-2800,1775)","0","mstr_standard","I42";
;
CDS_LIB"mstr_standard"
BODY_TYPE"PLUMBING"
HDL_TAP"TRUE";
"B \NAC \NWC"1;
"S \NAC"
BN"3"45;
%"TAP"
"1","(-2950,2475)","0","mstr_standard","I43";
;
CDS_LIB"mstr_standard"
BODY_TYPE"PLUMBING"
HDL_TAP"TRUE";
"B \NAC \NWC"2;
"S \NAC"
BN"6"48;
%"TAP"
"1","(-2950,2425)","0","mstr_standard","I44";
;
CDS_LIB"mstr_standard"
BODY_TYPE"PLUMBING"
HDL_TAP"TRUE";
"B \NAC \NWC"2;
"S \NAC"
BN"5"47;
%"TAP"
"1","(-2950,2375)","0","mstr_standard","I45";
;
CDS_LIB"mstr_standard"
BODY_TYPE"PLUMBING"
HDL_TAP"TRUE";
"B \NAC \NWC"2;
"S \NAC"
BN"4"46;
%"TAP"
"1","(-2950,2025)","0","mstr_standard","I46";
;
CDS_LIB"mstr_standard"
BODY_TYPE"PLUMBING"
HDL_TAP"TRUE";
"B \NAC \NWC"2;
"S \NAC"
BN"3"41;
%"TAP"
"1","(-2800,2125)","0","mstr_standard","I47";
;
CDS_LIB"mstr_standard"
BODY_TYPE"PLUMBING"
HDL_TAP"TRUE";
"B \NAC \NWC"1;
"S \NAC"
BN"4"58;
%"TAP"
"1","(-2800,2175)","0","mstr_standard","I48";
;
CDS_LIB"mstr_standard"
BODY_TYPE"PLUMBING"
HDL_TAP"TRUE";
"B \NAC \NWC"1;
"S \NAC"
BN"5"59;
%"TAP"
"1","(-2800,2225)","0","mstr_standard","I49";
;
CDS_LIB"mstr_standard"
BODY_TYPE"PLUMBING"
HDL_TAP"TRUE";
"B \NAC \NWC"1;
"S \NAC"
BN"6"60;
%"TAP"
"1","(-5575,1625)","2","mstr_standard","I5";
;
CDS_LIB"mstr_standard"
BODY_TYPE"PLUMBING"
HDL_TAP"TRUE";
"B \NAC \NWC"3;
"S \NAC"
BN"0"14;
%"TAP"
"1","(-2800,2275)","0","mstr_standard","I50";
;
CDS_LIB"mstr_standard"
BODY_TYPE"PLUMBING"
HDL_TAP"TRUE";
"B \NAC \NWC"1;
"S \NAC"
BN"7"61;
%"TAP"
"1","(-2950,2975)","0","mstr_standard","I51";
;
CDS_LIB"mstr_standard"
BODY_TYPE"PLUMBING"
HDL_TAP"TRUE";
"B \NAC \NWC"2;
"S \NAC"
BN"10"52;
%"TAP"
"1","(-2950,2925)","0","mstr_standard","I52";
;
CDS_LIB"mstr_standard"
BODY_TYPE"PLUMBING"
HDL_TAP"TRUE";
"B \NAC \NWC"2;
"S \NAC"
BN"9"51;
%"TAP"
"1","(-2950,2875)","0","mstr_standard","I53";
;
CDS_LIB"mstr_standard"
BODY_TYPE"PLUMBING"
HDL_TAP"TRUE";
"B \NAC \NWC"2;
"S \NAC"
BN"8"50;
%"TAP"
"1","(-2950,2525)","0","mstr_standard","I54";
;
CDS_LIB"mstr_standard"
BODY_TYPE"PLUMBING"
HDL_TAP"TRUE";
"B \NAC \NWC"2;
"S \NAC"
BN"7"49;
%"TAP"
"1","(-2800,2625)","0","mstr_standard","I55";
;
CDS_LIB"mstr_standard"
BODY_TYPE"PLUMBING"
HDL_TAP"TRUE";
"B \NAC \NWC"1;
"S \NAC"
BN"8"62;
%"TAP"
"1","(-2800,2725)","0","mstr_standard","I56";
;
CDS_LIB"mstr_standard"
BODY_TYPE"PLUMBING"
HDL_TAP"TRUE";
"B \NAC \NWC"1;
"S \NAC"
BN"10"64;
%"TAP"
"1","(-2800,2675)","0","mstr_standard","I57";
;
CDS_LIB"mstr_standard"
BODY_TYPE"PLUMBING"
HDL_TAP"TRUE";
"B \NAC \NWC"1;
"S \NAC"
BN"9"63;
%"TAP"
"1","(-2800,2775)","0","mstr_standard","I58";
;
CDS_LIB"mstr_standard"
BODY_TYPE"PLUMBING"
HDL_TAP"TRUE";
"B \NAC \NWC"1;
"S \NAC"
BN"11"65;
%"TAP"
"1","(-2950,3525)","0","mstr_standard","I59";
;
CDS_LIB"mstr_standard"
BODY_TYPE"PLUMBING"
HDL_TAP"TRUE";
"B \NAC \NWC"2;
"S \NAC"
BN"15"57;
%"TAP"
"1","(-5575,1775)","2","mstr_standard","I6";
;
CDS_LIB"mstr_standard"
BODY_TYPE"PLUMBING"
HDL_TAP"TRUE";
"B \NAC \NWC"3;
"S \NAC"
BN"3"17;
%"TAP"
"1","(-2950,3475)","0","mstr_standard","I60";
;
CDS_LIB"mstr_standard"
BODY_TYPE"PLUMBING"
HDL_TAP"TRUE";
"B \NAC \NWC"2;
"S \NAC"
BN"14"56;
%"TAP"
"1","(-2950,3425)","0","mstr_standard","I61";
;
CDS_LIB"mstr_standard"
BODY_TYPE"PLUMBING"
HDL_TAP"TRUE";
"B \NAC \NWC"2;
"S \NAC"
BN"13"55;
%"TAP"
"1","(-2950,3375)","0","mstr_standard","I62";
;
CDS_LIB"mstr_standard"
BODY_TYPE"PLUMBING"
HDL_TAP"TRUE";
"B \NAC \NWC"2;
"S \NAC"
BN"12"54;
%"TAP"
"1","(-2950,3025)","0","mstr_standard","I63";
;
CDS_LIB"mstr_standard"
BODY_TYPE"PLUMBING"
HDL_TAP"TRUE";
"B \NAC \NWC"2;
"S \NAC"
BN"11"53;
%"TAP"
"1","(-2800,3125)","0","mstr_standard","I64";
;
CDS_LIB"mstr_standard"
BODY_TYPE"PLUMBING"
HDL_TAP"TRUE";
"B \NAC \NWC"1;
"S \NAC"
BN"12"66;
%"TAP"
"1","(-2800,3175)","0","mstr_standard","I65";
;
CDS_LIB"mstr_standard"
BODY_TYPE"PLUMBING"
HDL_TAP"TRUE";
"B \NAC \NWC"1;
"S \NAC"
BN"13"67;
%"TAP"
"1","(-2800,3275)","0","mstr_standard","I66";
;
CDS_LIB"mstr_standard"
BODY_TYPE"PLUMBING"
HDL_TAP"TRUE";
"B \NAC \NWC"1;
"S \NAC"
BN"15"68;
%"TAP"
"1","(-2800,3225)","0","mstr_standard","I67";
;
CDS_LIB"mstr_standard"
BODY_TYPE"PLUMBING"
HDL_TAP"TRUE";
"B \NAC \NWC"1;
"S \NAC"
BN"14"5;
%"SKX_EXT_B"
"11","(-4150,2575)","0","chpset_lib","I68";
;
CDS_SEC"11"
LOCATION"U2D1"
PART_NUMBER"TBD"
MATERIAL"IC"
PACK_TYPE"BGA1"
SEC_TYPE"BGA1"
CDS_LIB"chpset_lib"
SEC"11"
CDS_LOCATION"U2D1";
"PE2_TX_DP<0>"
$PN"CW4"38;
"PE2_TX_DP<1>"
$PN"CU2"39;
"PE2_TX_DP<2>"
$PN"CR2"40;
"PE2_TX_DP<3>"
$PN"CP3"41;
"PE2_TX_DP<4>"
$PN"CK1"46;
"PE2_TX_DP<5>"
$PN"CK3"47;
"PE2_TX_DP<6>"
$PN"CE2"48;
"PE2_TX_DP<7>"
$PN"CE4"49;
"PE2_TX_DP<8>"
$PN"CD3"50;
"PE2_TX_DP<9>"
$PN"BY3"51;
"PE2_TX_DP<10>"
$PN"BY5"52;
"PE2_TX_DP<11>"
$PN"BV3"53;
"PE2_TX_DP<12>"
$PN"BR4"54;
"PE2_TX_DP<13>"
$PN"BN4"55;
"PE2_TX_DP<14>"
$PN"BM3"56;
"PE2_TX_DP<15>"
$PN"BK5"57;
"PE2_TX_DN<0>"
$PN"CY3"42;
"PE2_TX_DN<1>"
$PN"CV3"43;
"PE2_TX_DN<2>"
$PN"CT1"44;
"PE2_TX_DN<3>"
$PN"CT3"45;
"PE2_TX_DN<4>"
$PN"CM1"58;
"PE2_TX_DN<5>"
$PN"CL2"59;
"PE2_TX_DN<6>"
$PN"CG2"60;
"PE2_TX_DN<7>"
$PN"CF3"61;
"PE2_TX_DN<8>"
$PN"CC2"62;
"PE2_TX_DN<9>"
$PN"CB3"63;
"PE2_TX_DN<10>"
$PN"CA4"64;
"PE2_TX_DN<11>"
$PN"BW4"65;
"PE2_TX_DN<12>"
$PN"BU4"66;
"PE2_TX_DN<13>"
$PN"BP5"67;
"PE2_TX_DN<14>"
$PN"BL4"5;
"PE2_TX_DN<15>"
$PN"BM5"68;
"PE2_RX_DP<0>"
$PN"CR8"10;
"PE2_RX_DP<1>"
$PN"CM9"11;
"PE2_RX_DP<2>"
$PN"CN8"12;
"PE2_RX_DP<3>"
$PN"CL6"13;
"PE2_RX_DP<4>"
$PN"CH7"18;
"PE2_RX_DP<5>"
$PN"CF7"19;
"PE2_RX_DP<6>"
$PN"CD7"20;
"PE2_RX_DP<7>"
$PN"CC8"21;
"PE2_RX_DP<8>"
$PN"BV9"22;
"PE2_RX_DP<9>"
$PN"BW8"6;
"PE2_RX_DP<10>"
$PN"BU6"9;
"PE2_RX_DP<11>"
$PN"BP7"7;
"PE2_RX_DP<12>"
$PN"BP9"23;
"PE2_RX_DP<13>"
$PN"BM7"24;
"PE2_RX_DP<14>"
$PN"BJ8"25;
"PE2_RX_DP<15>"
$PN"BJ10"26;
"PE2_RX_DN<0>"
$PN"CT9"14;
"PE2_RX_DN<1>"
$PN"CP9"15;
"PE2_RX_DN<2>"
$PN"CP7"16;
"PE2_RX_DN<3>"
$PN"CM7"17;
"PE2_RX_DN<4>"
$PN"CK7"27;
"PE2_RX_DN<5>"
$PN"CG8"28;
"PE2_RX_DN<6>"
$PN"CE6"29;
"PE2_RX_DN<7>"
$PN"CE8"30;
"PE2_RX_DN<8>"
$PN"BY9"31;
"PE2_RX_DN<9>"
$PN"BY7"32;
"PE2_RX_DN<10>"
$PN"BV7"33;
"PE2_RX_DN<11>"
$PN"BT7"34;
"PE2_RX_DN<12>"
$PN"BR8"35;
"PE2_RX_DN<13>"
$PN"BN8"36;
"PE2_RX_DN<14>"
$PN"BL8"8;
"PE2_RX_DN<15>"
$PN"BK9"37;
%"TAP"
"1","(-5425,1975)","2","mstr_standard","I7";
;
CDS_LIB"mstr_standard"
BODY_TYPE"PLUMBING"
HDL_TAP"TRUE";
"B \NAC \NWC"4;
"S \NAC"
BN"2"12;
%"TAP"
"1","(-5425,1925)","2","mstr_standard","I8";
;
CDS_LIB"mstr_standard"
BODY_TYPE"PLUMBING"
HDL_TAP"TRUE";
"B \NAC \NWC"4;
"S \NAC"
BN"1"11;
%"TAP"
"1","(-5425,1875)","2","mstr_standard","I9";
;
CDS_LIB"mstr_standard"
BODY_TYPE"PLUMBING"
HDL_TAP"TRUE";
"B \NAC \NWC"4;
"S \NAC"
BN"0"10;
END.
